(kicad_pcb
	(version 20260206)
	(generator "pcbnew")
	(generator_version "10.0")
	(general
		(thickness 1.6)
		(legacy_teardrops no)
	)
	(paper "A4")
	(title_block
		(title "12092022_DA0F0TMDCD0_F0T_Management_Board_D_brd_V3_OCP.brd")
		(comment 1 "Grand Teton / footprints 1434-1439 of 1440")
	)
	(layers
		(0 "F.Cu" signal "TOP")
		(4 "In1.Cu" signal "GND")
		(6 "In2.Cu" signal "IN1")
		(8 "In3.Cu" signal "GND1")
		(10 "In4.Cu" signal "IN2")
		(12 "In5.Cu" signal "VCC")
		(14 "In6.Cu" signal "VCC1")
		(16 "In7.Cu" signal "IN3")
		(18 "In8.Cu" signal "GND2")
		(20 "In9.Cu" signal "IN4")
		(22 "In10.Cu" signal "GND3")
		(2 "B.Cu" signal "BOTTOM")
		(9 "F.Adhes" user "F.Adhesive")
		(11 "B.Adhes" user "B.Adhesive")
		(13 "F.Paste" user "Package Geometry/Pastemask Top")
		(15 "B.Paste" user "Package Geometry/Pastemask Bottom")
		(5 "F.SilkS" user "Ref Des/Silkscreen Top")
		(7 "B.SilkS" user "Ref Des/Silkscreen Bottom")
		(1 "F.Mask" user "Board Geometry/Soldermask Top")
		(3 "B.Mask" user "Board Geometry/Soldermask Bottom")
		(17 "Dwgs.User" user "User.Drawings")
		(19 "Cmts.User" user "User.Comments")
		(21 "Eco1.User" user "User.Eco1")
		(23 "Eco2.User" user "User.Eco2")
		(25 "Edge.Cuts" user "Board Geometry/Outline")
		(27 "Margin" user)
		(31 "F.CrtYd" user "Package Geometry/Place Bound Top")
		(29 "B.CrtYd" user "Package Geometry/Place Bound Bottom")
		(35 "F.Fab" user "Ref Des/Assembly Top")
		(33 "B.Fab" user "Ref Des/Assembly Bottom")
	)
	(footprint ""
		(layer "B.Cu")
		(at 83.16722 -45.570394)
		(property "Reference" "R338"
			(at 0 0 0)
			(layer "B.SilkS")
			(hide yes)
			(effects
				(font
					(size 1.27 1.27)
				)
				(justify mirror)
			)
		)
		(property "Value" ""
			(at 0 0 0)
			(layer "B.Fab")
			(effects
				(font
					(size 1.27 1.27)
				)
				(justify mirror)
			)
		)
		(duplicate_pad_numbers_are_jumpers no)
		(fp_line
			(start -0.7874 -0.4064)
			(end -0.7874 0.4064)
			(stroke
				(width 0.1524)
				(type default)
			)
			(layer "B.SilkS")
		)
		(fp_line
			(start -0.7874 0.4064)
			(end 0.7874 0.4064)
			(stroke
				(width 0.1524)
				(type default)
			)
			(layer "B.SilkS")
		)
		(fp_line
			(start 0.7874 -0.4064)
			(end -0.7874 -0.4064)
			(stroke
				(width 0.1524)
				(type default)
			)
			(layer "B.SilkS")
		)
		(fp_line
			(start 0.7874 0.4064)
			(end 0.7874 -0.4064)
			(stroke
				(width 0.1524)
				(type default)
			)
			(layer "B.SilkS")
		)
		(fp_line
			(start -0.67945 -0.3048)
			(end -0.67945 0.3048)
			(stroke
				(width 0.1)
				(type default)
			)
			(layer "B.Fab")
		)
		(fp_line
			(start -0.67945 0.3048)
			(end -0.120396 0.3048)
			(stroke
				(width 0.1)
				(type default)
			)
			(layer "B.Fab")
		)
		(fp_line
			(start -0.12065 -0.3048)
			(end -0.67945 -0.3048)
			(stroke
				(width 0.1)
				(type default)
			)
			(layer "B.Fab")
		)
		(fp_line
			(start -0.12065 -0.2794)
			(end -0.12065 -0.3048)
			(stroke
				(width 0.1)
				(type default)
			)
			(layer "B.Fab")
		)
		(fp_line
			(start -0.120396 0.2794)
			(end 0.12065 0.2794)
			(stroke
				(width 0.1)
				(type default)
			)
			(layer "B.Fab")
		)
		(fp_line
			(start -0.120396 0.3048)
			(end -0.120396 0.2794)
			(stroke
				(width 0.1)
				(type default)
			)
			(layer "B.Fab")
		)
		(fp_line
			(start 0.12065 -0.305054)
			(end 0.12065 -0.2794)
			(stroke
				(width 0.1)
				(type default)
			)
			(layer "B.Fab")
		)
		(fp_line
			(start 0.12065 -0.2794)
			(end -0.12065 -0.2794)
			(stroke
				(width 0.1)
				(type default)
			)
			(layer "B.Fab")
		)
		(fp_line
			(start 0.12065 0.2794)
			(end 0.12065 0.3048)
			(stroke
				(width 0.1)
				(type default)
			)
			(layer "B.Fab")
		)
		(fp_line
			(start 0.12065 0.3048)
			(end 0.67945 0.3048)
			(stroke
				(width 0.1)
				(type default)
			)
			(layer "B.Fab")
		)
		(fp_line
			(start 0.67945 -0.305054)
			(end 0.12065 -0.305054)
			(stroke
				(width 0.1)
				(type default)
			)
			(layer "B.Fab")
		)
		(fp_line
			(start 0.67945 0.3048)
			(end 0.67945 -0.305054)
			(stroke
				(width 0.1)
				(type default)
			)
			(layer "B.Fab")
		)
		(pad "1" smd circle
			(at 0.40005 0 180)
			(size 0 0)
			(layers "B.Cu" "B.Mask" "B.Paste")
			(net "GND")
		)
		(pad "2" smd circle
			(at -0.40005 0 180)
			(size 0 0)
			(layers "B.Cu" "B.Mask" "B.Paste")
			(net "M_BMC_DDR4_MA<12>")
		)
	)
	(footprint ""
		(layer "B.Cu")
		(at 42.4688 -59.2074 180)
		(property "Reference" "L12"
			(at 0 0 0)
			(layer "B.SilkS")
			(hide yes)
			(effects
				(font
					(size 1.27 1.27)
				)
				(justify mirror)
			)
		)
		(property "Value" ""
			(at 0 0 0)
			(layer "B.Fab")
			(effects
				(font
					(size 1.27 1.27)
				)
				(justify mirror)
			)
		)
		(duplicate_pad_numbers_are_jumpers no)
		(fp_line
			(start 1.27 0.5842)
			(end 1.27 -0.5842)
			(stroke
				(width 0.1524)
				(type default)
			)
			(layer "B.SilkS")
		)
		(fp_line
			(start 1.27 -0.5588)
			(end 1.27 -0.5842)
			(stroke
				(width 0.1524)
				(type default)
			)
			(layer "B.SilkS")
		)
		(fp_line
			(start 1.27 -0.5842)
			(end -1.27 -0.5842)
			(stroke
				(width 0.1524)
				(type default)
			)
			(layer "B.SilkS")
		)
		(fp_line
			(start 0.127 0.5842)
			(end 0.127 -0.5842)
			(stroke
				(width 0.1524)
				(type default)
			)
			(layer "B.SilkS")
		)
		(fp_line
			(start -0.127 0.5842)
			(end -0.127 -0.5842)
			(stroke
				(width 0.1524)
				(type default)
			)
			(layer "B.SilkS")
		)
		(fp_line
			(start -1.27 0.5842)
			(end 1.27 0.5842)
			(stroke
				(width 0.1524)
				(type default)
			)
			(layer "B.SilkS")
		)
		(fp_line
			(start -1.27 0.5842)
			(end -1.27 -0.5842)
			(stroke
				(width 0.1524)
				(type default)
			)
			(layer "B.SilkS")
		)
		(fp_line
			(start 1.194308 0.406654)
			(end 1.194308 -0.406654)
			(stroke
				(width 0.1)
				(type default)
			)
			(layer "B.Fab")
		)
		(fp_line
			(start 1.194308 -0.406654)
			(end 0.9144 -0.406654)
			(stroke
				(width 0.1)
				(type default)
			)
			(layer "B.Fab")
		)
		(fp_line
			(start 0.9144 0.508)
			(end 0.9144 0.406654)
			(stroke
				(width 0.1)
				(type default)
			)
			(layer "B.Fab")
		)
		(fp_line
			(start 0.9144 0.406654)
			(end 1.194308 0.406654)
			(stroke
				(width 0.1)
				(type default)
			)
			(layer "B.Fab")
		)
		(fp_line
			(start 0.9144 -0.406654)
			(end 0.9144 -0.508)
			(stroke
				(width 0.1)
				(type default)
			)
			(layer "B.Fab")
		)
		(fp_line
			(start 0.9144 -0.508)
			(end -0.9144 -0.508)
			(stroke
				(width 0.1)
				(type default)
			)
			(layer "B.Fab")
		)
		(fp_line
			(start -0.9144 0.508)
			(end 0.9144 0.508)
			(stroke
				(width 0.1)
				(type default)
			)
			(layer "B.Fab")
		)
		(fp_line
			(start -0.9144 0.4064)
			(end -0.9144 0.508)
			(stroke
				(width 0.1)
				(type default)
			)
			(layer "B.Fab")
		)
		(fp_line
			(start -0.9144 -0.406654)
			(end -1.1938 -0.406654)
			(stroke
				(width 0.1)
				(type default)
			)
			(layer "B.Fab")
		)
		(fp_line
			(start -0.9144 -0.508)
			(end -0.9144 -0.406654)
			(stroke
				(width 0.1)
				(type default)
			)
			(layer "B.Fab")
		)
		(fp_line
			(start -1.1938 0.4064)
			(end -0.9144 0.4064)
			(stroke
				(width 0.1)
				(type default)
			)
			(layer "B.Fab")
		)
		(fp_line
			(start -1.1938 -0.406654)
			(end -1.1938 0.4064)
			(stroke
				(width 0.1)
				(type default)
			)
			(layer "B.Fab")
		)
		(pad "1" smd rect
			(at 0.7366 0 90)
			(size 0.7112 0.8128)
			(layers "B.Cu" "B.Mask" "B.Paste")
			(net "P3V3_AUX")
		)
		(pad "2" smd rect
			(at -0.7366 0 90)
			(size 0.7112 0.8128)
			(layers "B.Cu" "B.Mask" "B.Paste")
			(net "A_BMC_ADCAV33")
		)
	)
	(footprint ""
		(layer "B.Cu")
		(at -14.2494 -66.929 180)
		(property "Reference" "DB3"
			(at 2.71526 -6.12521 0)
			(unlocked yes)
			(layer "B.SilkS")
			(effects
				(font
					(size 0.7874 0.5842)
					(thickness 0.1524)
				)
				(justify left mirror)
			)
		)
		(property "Value" ""
			(at 0 0 0)
			(layer "B.Fab")
			(effects
				(font
					(size 1.27 1.27)
				)
				(justify mirror)
			)
		)
		(duplicate_pad_numbers_are_jumpers no)
		(fp_line
			(start 3.330702 -4.771136)
			(end -3.330702 -4.771136)
			(stroke
				(width 0.1524)
				(type default)
			)
			(layer "B.SilkS")
		)
		(fp_line
			(start 0 4.011168)
			(end 3.330702 -4.771136)
			(stroke
				(width 0.1524)
				(type default)
			)
			(layer "B.SilkS")
		)
		(fp_line
			(start -3.330702 -4.771136)
			(end 0 4.011168)
			(stroke
				(width 0.1524)
				(type default)
			)
			(layer "B.SilkS")
		)
		(fp_line
			(start 3.330702 -4.771136)
			(end -3.330702 -4.771136)
			(stroke
				(width 0.1)
				(type default)
			)
			(layer "B.Fab")
		)
		(fp_line
			(start 0 4.011168)
			(end 3.330702 -4.771136)
			(stroke
				(width 0.1)
				(type default)
			)
			(layer "B.Fab")
		)
		(fp_line
			(start -3.330702 -4.771136)
			(end 0 4.011168)
			(stroke
				(width 0.1)
				(type default)
			)
			(layer "B.Fab")
		)
		(pad "1" thru_hole circle
			(at 0 0)
			(size 2.159 2.159)
			(drill 1.7018)
			(layers "*.Cu" "*.Mask")
			(remove_unused_layers no)
			(net "T_GND")
			(clearance 0.0254)
			(thermal_gap 0.0254)
		)
		(pad "2" thru_hole circle
			(at 1.27 -3.348736)
			(size 2.159 2.159)
			(drill 1.7018)
			(layers "*.Cu" "*.Mask")
			(remove_unused_layers no)
			(net "TDR_SE_50_OHM_IN2")
			(clearance 0.0254)
			(thermal_gap 0.0254)
		)
		(pad "3" thru_hole circle
			(at -1.27 -3.348736)
			(size 2.159 2.159)
			(drill 1.7018)
			(layers "*.Cu" "*.Mask")
			(remove_unused_layers no)
			(net "TDR_SE_50_OHM_IN2")
			(clearance 0.0254)
			(thermal_gap 0.0254)
		)
	)
	(footprint ""
		(layer "B.Cu")
		(at 41.143936 -52.40147 180)
		(property "Reference" "R281"
			(at 0 0 0)
			(layer "B.SilkS")
			(hide yes)
			(effects
				(font
					(size 1.27 1.27)
				)
				(justify mirror)
			)
		)
		(property "Value" ""
			(at 0 0 0)
			(layer "B.Fab")
			(effects
				(font
					(size 1.27 1.27)
				)
				(justify mirror)
			)
		)
		(duplicate_pad_numbers_are_jumpers no)
		(fp_line
			(start 0.7874 0.4064)
			(end 0.7874 -0.4064)
			(stroke
				(width 0.1524)
				(type default)
			)
			(layer "B.SilkS")
		)
		(fp_line
			(start 0.7874 -0.4064)
			(end -0.7874 -0.4064)
			(stroke
				(width 0.1524)
				(type default)
			)
			(layer "B.SilkS")
		)
		(fp_line
			(start -0.7874 0.4064)
			(end 0.7874 0.4064)
			(stroke
				(width 0.1524)
				(type default)
			)
			(layer "B.SilkS")
		)
		(fp_line
			(start -0.7874 -0.4064)
			(end -0.7874 0.4064)
			(stroke
				(width 0.1524)
				(type default)
			)
			(layer "B.SilkS")
		)
		(fp_line
			(start 0.67945 0.3048)
			(end 0.67945 -0.305054)
			(stroke
				(width 0.1)
				(type default)
			)
			(layer "B.Fab")
		)
		(fp_line
			(start 0.67945 -0.305054)
			(end 0.12065 -0.305054)
			(stroke
				(width 0.1)
				(type default)
			)
			(layer "B.Fab")
		)
		(fp_line
			(start 0.12065 0.3048)
			(end 0.67945 0.3048)
			(stroke
				(width 0.1)
				(type default)
			)
			(layer "B.Fab")
		)
		(fp_line
			(start 0.12065 0.2794)
			(end 0.12065 0.3048)
			(stroke
				(width 0.1)
				(type default)
			)
			(layer "B.Fab")
		)
		(fp_line
			(start 0.12065 -0.2794)
			(end -0.12065 -0.2794)
			(stroke
				(width 0.1)
				(type default)
			)
			(layer "B.Fab")
		)
		(fp_line
			(start 0.12065 -0.305054)
			(end 0.12065 -0.2794)
			(stroke
				(width 0.1)
				(type default)
			)
			(layer "B.Fab")
		)
		(fp_line
			(start -0.120396 0.3048)
			(end -0.120396 0.2794)
			(stroke
				(width 0.1)
				(type default)
			)
			(layer "B.Fab")
		)
		(fp_line
			(start -0.120396 0.2794)
			(end 0.12065 0.2794)
			(stroke
				(width 0.1)
				(type default)
			)
			(layer "B.Fab")
		)
		(fp_line
			(start -0.12065 -0.2794)
			(end -0.12065 -0.3048)
			(stroke
				(width 0.1)
				(type default)
			)
			(layer "B.Fab")
		)
		(fp_line
			(start -0.12065 -0.3048)
			(end -0.67945 -0.3048)
			(stroke
				(width 0.1)
				(type default)
			)
			(layer "B.Fab")
		)
		(fp_line
			(start -0.67945 0.3048)
			(end -0.120396 0.3048)
			(stroke
				(width 0.1)
				(type default)
			)
			(layer "B.Fab")
		)
		(fp_line
			(start -0.67945 -0.3048)
			(end -0.67945 0.3048)
			(stroke
				(width 0.1)
				(type default)
			)
			(layer "B.Fab")
		)
		(pad "1" smd circle
			(at 0.40005 0)
			(size 0 0)
			(layers "B.Cu" "B.Mask" "B.Paste")
			(net "P1V0_AUX")
		)
		(pad "2" smd circle
			(at -0.40005 0)
			(size 0 0)
			(layers "B.Cu" "B.Mask" "B.Paste")
			(net "P1V2_P1V0_I3C_VDDL2")
		)
	)
	(footprint ""
		(layer "B.Cu")
		(at 18.2626 -78.359 -90)
		(property "Reference" "R806"
			(at 0 0 90)
			(layer "B.SilkS")
			(hide yes)
			(effects
				(font
					(size 1.27 1.27)
				)
				(justify mirror)
			)
		)
		(property "Value" ""
			(at 0 0 90)
			(layer "B.Fab")
			(effects
				(font
					(size 1.27 1.27)
				)
				(justify mirror)
			)
		)
		(duplicate_pad_numbers_are_jumpers no)
		(fp_line
			(start -0.7874 0.4064)
			(end 0.7874 0.4064)
			(stroke
				(width 0.1524)
				(type default)
			)
			(layer "B.SilkS")
		)
		(fp_line
			(start 0.7874 0.4064)
			(end 0.7874 -0.4064)
			(stroke
				(width 0.1524)
				(type default)
			)
			(layer "B.SilkS")
		)
		(fp_line
			(start -0.7874 -0.4064)
			(end -0.7874 0.4064)
			(stroke
				(width 0.1524)
				(type default)
			)
			(layer "B.SilkS")
		)
		(fp_line
			(start 0.7874 -0.4064)
			(end -0.7874 -0.4064)
			(stroke
				(width 0.1524)
				(type default)
			)
			(layer "B.SilkS")
		)
		(fp_line
			(start -0.67945 0.3048)
			(end -0.120396 0.3048)
			(stroke
				(width 0.1)
				(type default)
			)
			(layer "B.Fab")
		)
		(fp_line
			(start -0.120396 0.3048)
			(end -0.120396 0.2794)
			(stroke
				(width 0.1)
				(type default)
			)
			(layer "B.Fab")
		)
		(fp_line
			(start 0.12065 0.3048)
			(end 0.67945 0.3048)
			(stroke
				(width 0.1)
				(type default)
			)
			(layer "B.Fab")
		)
		(fp_line
			(start 0.67945 0.3048)
			(end 0.67945 -0.305054)
			(stroke
				(width 0.1)
				(type default)
			)
			(layer "B.Fab")
		)
		(fp_line
			(start -0.120396 0.2794)
			(end 0.12065 0.2794)
			(stroke
				(width 0.1)
				(type default)
			)
			(layer "B.Fab")
		)
		(fp_line
			(start 0.12065 0.2794)
			(end 0.12065 0.3048)
			(stroke
				(width 0.1)
				(type default)
			)
			(layer "B.Fab")
		)
		(fp_line
			(start -0.12065 -0.2794)
			(end -0.12065 -0.3048)
			(stroke
				(width 0.1)
				(type default)
			)
			(layer "B.Fab")
		)
		(fp_line
			(start 0.12065 -0.2794)
			(end -0.12065 -0.2794)
			(stroke
				(width 0.1)
				(type default)
			)
			(layer "B.Fab")
		)
		(fp_line
			(start -0.67945 -0.3048)
			(end -0.67945 0.3048)
			(stroke
				(width 0.1)
				(type default)
			)
			(layer "B.Fab")
		)
		(fp_line
			(start -0.12065 -0.3048)
			(end -0.67945 -0.3048)
			(stroke
				(width 0.1)
				(type default)
			)
			(layer "B.Fab")
		)
		(fp_line
			(start 0.12065 -0.305054)
			(end 0.12065 -0.2794)
			(stroke
				(width 0.1)
				(type default)
			)
			(layer "B.Fab")
		)
		(fp_line
			(start 0.67945 -0.305054)
			(end 0.12065 -0.305054)
			(stroke
				(width 0.1)
				(type default)
			)
			(layer "B.Fab")
		)
		(pad "1" smd circle
			(at 0.40005 0 90)
			(size 0 0)
			(layers "B.Cu" "B.Mask" "B.Paste")
			(net "P3V3_AUX")
		)
		(pad "2" smd circle
			(at -0.40005 0 90)
			(size 0 0)
			(layers "B.Cu" "B.Mask" "B.Paste")
			(net "PU_25M_FPGA_CLK_EN")
		)
	)
	(footprint ""
		(layer "B.Cu")
		(at 53.04282 -51.69662)
		(property "Reference" "C82"
			(at 0 0 0)
			(layer "B.SilkS")
			(hide yes)
			(effects
				(font
					(size 1.27 1.27)
				)
				(justify mirror)
			)
		)
		(property "Value" ""
			(at 0 0 0)
			(layer "B.Fab")
			(effects
				(font
					(size 1.27 1.27)
				)
				(justify mirror)
			)
		)
		(duplicate_pad_numbers_are_jumpers no)
		(fp_line
			(start -0.7874 -0.4064)
			(end -0.7874 0.4064)
			(stroke
				(width 0.1524)
				(type default)
			)
			(layer "B.SilkS")
		)
		(fp_line
			(start -0.7874 0.4064)
			(end 0.7874 0.4064)
			(stroke
				(width 0.1524)
				(type default)
			)
			(layer "B.SilkS")
		)
		(fp_line
			(start 0.7874 -0.4064)
			(end -0.7874 -0.4064)
			(stroke
				(width 0.1524)
				(type default)
			)
			(layer "B.SilkS")
		)
		(fp_line
			(start 0.7874 0.4064)
			(end 0.7874 -0.4064)
			(stroke
				(width 0.1524)
				(type default)
			)
			(layer "B.SilkS")
		)
		(fp_line
			(start -0.67945 -0.3048)
			(end -0.67945 0.3048)
			(stroke
				(width 0.1)
				(type default)
			)
			(layer "B.Fab")
		)
		(fp_line
			(start -0.67945 0.3048)
			(end -0.120396 0.3048)
			(stroke
				(width 0.1)
				(type default)
			)
			(layer "B.Fab")
		)
		(fp_line
			(start -0.12065 -0.3048)
			(end -0.67945 -0.3048)
			(stroke
				(width 0.1)
				(type default)
			)
			(layer "B.Fab")
		)
		(fp_line
			(start -0.12065 -0.2794)
			(end -0.12065 -0.3048)
			(stroke
				(width 0.1)
				(type default)
			)
			(layer "B.Fab")
		)
		(fp_line
			(start -0.120396 0.2794)
			(end 0.12065 0.2794)
			(stroke
				(width 0.1)
				(type default)
			)
			(layer "B.Fab")
		)
		(fp_line
			(start -0.120396 0.3048)
			(end -0.120396 0.2794)
			(stroke
				(width 0.1)
				(type default)
			)
			(layer "B.Fab")
		)
		(fp_line
			(start 0.12065 -0.305054)
			(end 0.12065 -0.2794)
			(stroke
				(width 0.1)
				(type default)
			)
			(layer "B.Fab")
		)
		(fp_line
			(start 0.12065 -0.2794)
			(end -0.12065 -0.2794)
			(stroke
				(width 0.1)
				(type default)
			)
			(layer "B.Fab")
		)
		(fp_line
			(start 0.12065 0.2794)
			(end 0.12065 0.3048)
			(stroke
				(width 0.1)
				(type default)
			)
			(layer "B.Fab")
		)
		(fp_line
			(start 0.12065 0.3048)
			(end 0.67945 0.3048)
			(stroke
				(width 0.1)
				(type default)
			)
			(layer "B.Fab")
		)
		(fp_line
			(start 0.67945 -0.305054)
			(end 0.12065 -0.305054)
			(stroke
				(width 0.1)
				(type default)
			)
			(layer "B.Fab")
		)
		(fp_line
			(start 0.67945 0.3048)
			(end 0.67945 -0.305054)
			(stroke
				(width 0.1)
				(type default)
			)
			(layer "B.Fab")
		)
		(pad "1" smd circle
			(at 0.40005 0 180)
			(size 0 0)
			(layers "B.Cu" "B.Mask" "B.Paste")
			(net "P1V2_AUX")
		)
		(pad "2" smd circle
			(at -0.40005 0 180)
			(size 0 0)
			(layers "B.Cu" "B.Mask" "B.Paste")
			(net "GND")
		)
	)
)
